# T6G (Grand Teton) — schematic netlist excerpt (pin names and nets, part order shuffled) for the footprints in the layout excerpt that follows; sources: Cadence DE-HDL packaged netlist, KiCad conversion of 04192023_DAF0TMB3IC0_F0TG_MB_C_brd_V02_OCP.brd

R762  Q_RES  23.2K 1% CHIP  pkg 0402LF  page 88 : A = PD_CHC_CPU0_DIMM_SAA ; B = GND
PC342_2  Q_CAP  22UF 4V 20% X6S  pkg C0805  page 215 : A = PVDDCR_SOC_P1 ; B = GND
C6094  Q_CAP  0.01UF 50V 10% X7R  pkg C0402  page 179 : A = P3V3_AUX_CPU0_USB2_AVDD33 ; B = GND

(kicad_pcb
	(version 20260206)
	(generator "pcbnew")
	(generator_version "10.0")
	(general
		(thickness 1.6)
		(legacy_teardrops no)
	)
	(paper "A4")
	(title_block
		(title "04192023_DAF0TMB3IC0_F0TG_MB_C_brd_V02_OCP.brd")
		(comment 1 "Grand Teton / footprints 5240-5242 of 8354")
	)
	(layers
		(0 "F.Cu" signal "TOP")
		(4 "In1.Cu" signal "GND")
		(6 "In2.Cu" signal "IN1")
		(8 "In3.Cu" signal "GND1")
		(10 "In4.Cu" signal "IN2")
		(12 "In5.Cu" signal "GND2")
		(14 "In6.Cu" signal "IN3")
		(16 "In7.Cu" signal "GND3")
		(18 "In8.Cu" signal "VCC")
		(20 "In9.Cu" signal "VCC1")
		(22 "In10.Cu" signal "GND4")
		(24 "In11.Cu" signal "IN4")
		(26 "In12.Cu" signal "GND5")
		(28 "In13.Cu" signal "IN5")
		(30 "In14.Cu" signal "GND6")
		(32 "In15.Cu" signal "IN6")
		(34 "In16.Cu" signal "GND7")
		(2 "B.Cu" signal "BOTTOM")
		(9 "F.Adhes" user "F.Adhesive")
		(11 "B.Adhes" user "B.Adhesive")
		(13 "F.Paste" user "Package Geometry/Pastemask Top")
		(15 "B.Paste" user "Package Geometry/Pastemask Bottom")
		(5 "F.SilkS" user "Ref Des/Silkscreen Top")
		(7 "B.SilkS" user "Ref Des/Silkscreen Bottom")
		(1 "F.Mask" user "Board Geometry/Soldermask Top")
		(3 "B.Mask" user "Board Geometry/Soldermask Bottom")
		(17 "Dwgs.User" user "User.Drawings")
		(19 "Cmts.User" user "User.Comments")
		(21 "Eco1.User" user "User.Eco1")
		(23 "Eco2.User" user "User.Eco2")
		(25 "Edge.Cuts" user "Board Geometry/Outline")
		(27 "Margin" user)
		(31 "F.CrtYd" user "Package Geometry/Place Bound Top")
		(29 "B.CrtYd" user "Package Geometry/Place Bound Bottom")
		(35 "F.Fab" user "Ref Des/Assembly Top")
		(33 "B.Fab" user "Ref Des/Assembly Bottom")
	)
	(footprint ""
		(layer "B.Cu")
		(at 111.981996 -26.952448 90)
		(property "Reference" "C6094"
			(at 0 0 90)
			(layer "B.SilkS")
			(hide yes)
			(effects
				(font
					(size 1.27 1.27)
				)
				(justify mirror)
			)
		)
		(property "Value" ""
			(at 0 0 90)
			(layer "B.Fab")
			(effects
				(font
					(size 1.27 1.27)
				)
				(justify mirror)
			)
		)
		(duplicate_pad_numbers_are_jumpers no)
		(fp_line
			(start 0.7874 -0.4064)
			(end -0.7874 -0.4064)
			(stroke
				(width 0.1524)
				(type default)
			)
			(layer "B.SilkS")
		)
		(fp_line
			(start -0.7874 -0.4064)
			(end -0.7874 0.4064)
			(stroke
				(width 0.1524)
				(type default)
			)
			(layer "B.SilkS")
		)
		(fp_line
			(start 0.7874 0.4064)
			(end 0.7874 -0.4064)
			(stroke
				(width 0.1524)
				(type default)
			)
			(layer "B.SilkS")
		)
		(fp_line
			(start -0.7874 0.4064)
			(end 0.7874 0.4064)
			(stroke
				(width 0.1524)
				(type default)
			)
			(layer "B.SilkS")
		)
		(fp_line
			(start 0.67945 -0.305054)
			(end 0.12065 -0.305054)
			(stroke
				(width 0.1)
				(type default)
			)
			(layer "B.Fab")
		)
		(fp_line
			(start 0.12065 -0.305054)
			(end 0.12065 -0.2794)
			(stroke
				(width 0.1)
				(type default)
			)
			(layer "B.Fab")
		)
		(fp_line
			(start -0.12065 -0.3048)
			(end -0.67945 -0.3048)
			(stroke
				(width 0.1)
				(type default)
			)
			(layer "B.Fab")
		)
		(fp_line
			(start -0.67945 -0.3048)
			(end -0.67945 0.3048)
			(stroke
				(width 0.1)
				(type default)
			)
			(layer "B.Fab")
		)
		(fp_line
			(start 0.12065 -0.2794)
			(end -0.12065 -0.2794)
			(stroke
				(width 0.1)
				(type default)
			)
			(layer "B.Fab")
		)
		(fp_line
			(start -0.12065 -0.2794)
			(end -0.12065 -0.3048)
			(stroke
				(width 0.1)
				(type default)
			)
			(layer "B.Fab")
		)
		(fp_line
			(start 0.12065 0.2794)
			(end 0.12065 0.3048)
			(stroke
				(width 0.1)
				(type default)
			)
			(layer "B.Fab")
		)
		(fp_line
			(start -0.120396 0.2794)
			(end 0.12065 0.2794)
			(stroke
				(width 0.1)
				(type default)
			)
			(layer "B.Fab")
		)
		(fp_line
			(start 0.67945 0.3048)
			(end 0.67945 -0.305054)
			(stroke
				(width 0.1)
				(type default)
			)
			(layer "B.Fab")
		)
		(fp_line
			(start 0.12065 0.3048)
			(end 0.67945 0.3048)
			(stroke
				(width 0.1)
				(type default)
			)
			(layer "B.Fab")
		)
		(fp_line
			(start -0.120396 0.3048)
			(end -0.120396 0.2794)
			(stroke
				(width 0.1)
				(type default)
			)
			(layer "B.Fab")
		)
		(fp_line
			(start -0.67945 0.3048)
			(end -0.120396 0.3048)
			(stroke
				(width 0.1)
				(type default)
			)
			(layer "B.Fab")
		)
		(pad "1" smd circle
			(at 0.40005 0 270)
			(size 0 0)
			(layers "B.Cu" "B.Mask" "B.Paste")
			(net "P3V3_AUX_CPU0_USB2_AVDD33")
		)
		(pad "2" smd circle
			(at -0.40005 0 270)
			(size 0 0)
			(layers "B.Cu" "B.Mask" "B.Paste")
			(net "GND")
		)
	)
	(footprint ""
		(layer "B.Cu")
		(at 288.935668 -194.88531 180)
		(property "Reference" "R762"
			(at 0 0 0)
			(layer "B.SilkS")
			(hide yes)
			(effects
				(font
					(size 1.27 1.27)
				)
				(justify mirror)
			)
		)
		(property "Value" ""
			(at 0 0 0)
			(layer "B.Fab")
			(effects
				(font
					(size 1.27 1.27)
				)
				(justify mirror)
			)
		)
		(duplicate_pad_numbers_are_jumpers no)
		(fp_line
			(start 0.7874 0.4064)
			(end 0.7874 -0.4064)
			(stroke
				(width 0.1524)
				(type default)
			)
			(layer "B.SilkS")
		)
		(fp_line
			(start 0.7874 -0.4064)
			(end -0.7874 -0.4064)
			(stroke
				(width 0.1524)
				(type default)
			)
			(layer "B.SilkS")
		)
		(fp_line
			(start -0.7874 0.4064)
			(end 0.7874 0.4064)
			(stroke
				(width 0.1524)
				(type default)
			)
			(layer "B.SilkS")
		)
		(fp_line
			(start -0.7874 -0.4064)
			(end -0.7874 0.4064)
			(stroke
				(width 0.1524)
				(type default)
			)
			(layer "B.SilkS")
		)
		(fp_line
			(start 0.67945 0.3048)
			(end 0.67945 -0.305054)
			(stroke
				(width 0.1)
				(type default)
			)
			(layer "B.Fab")
		)
		(fp_line
			(start 0.67945 -0.305054)
			(end 0.12065 -0.305054)
			(stroke
				(width 0.1)
				(type default)
			)
			(layer "B.Fab")
		)
		(fp_line
			(start 0.12065 0.3048)
			(end 0.67945 0.3048)
			(stroke
				(width 0.1)
				(type default)
			)
			(layer "B.Fab")
		)
		(fp_line
			(start 0.12065 0.2794)
			(end 0.12065 0.3048)
			(stroke
				(width 0.1)
				(type default)
			)
			(layer "B.Fab")
		)
		(fp_line
			(start 0.12065 -0.2794)
			(end -0.12065 -0.2794)
			(stroke
				(width 0.1)
				(type default)
			)
			(layer "B.Fab")
		)
		(fp_line
			(start 0.12065 -0.305054)
			(end 0.12065 -0.2794)
			(stroke
				(width 0.1)
				(type default)
			)
			(layer "B.Fab")
		)
		(fp_line
			(start -0.120396 0.3048)
			(end -0.120396 0.2794)
			(stroke
				(width 0.1)
				(type default)
			)
			(layer "B.Fab")
		)
		(fp_line
			(start -0.120396 0.2794)
			(end 0.12065 0.2794)
			(stroke
				(width 0.1)
				(type default)
			)
			(layer "B.Fab")
		)
		(fp_line
			(start -0.12065 -0.2794)
			(end -0.12065 -0.3048)
			(stroke
				(width 0.1)
				(type default)
			)
			(layer "B.Fab")
		)
		(fp_line
			(start -0.12065 -0.3048)
			(end -0.67945 -0.3048)
			(stroke
				(width 0.1)
				(type default)
			)
			(layer "B.Fab")
		)
		(fp_line
			(start -0.67945 0.3048)
			(end -0.120396 0.3048)
			(stroke
				(width 0.1)
				(type default)
			)
			(layer "B.Fab")
		)
		(fp_line
			(start -0.67945 -0.3048)
			(end -0.67945 0.3048)
			(stroke
				(width 0.1)
				(type default)
			)
			(layer "B.Fab")
		)
		(pad "1" smd circle
			(at 0.40005 0)
			(size 0 0)
			(layers "B.Cu" "B.Mask" "B.Paste")
			(net "PD_CHC_CPU0_DIMM_SAA")
		)
		(pad "2" smd circle
			(at -0.40005 0)
			(size 0 0)
			(layers "B.Cu" "B.Mask" "B.Paste")
			(net "GND")
		)
	)
	(footprint ""
		(layer "B.Cu")
		(at 133.332474 -165.190932 90)
		(property "Reference" "PC342_2"
			(at 0 0 90)
			(layer "B.SilkS")
			(hide yes)
			(effects
				(font
					(size 1.27 1.27)
				)
				(justify mirror)
			)
		)
		(property "Value" ""
			(at 0 0 90)
			(layer "B.Fab")
			(effects
				(font
					(size 1.27 1.27)
				)
				(justify mirror)
			)
		)
		(duplicate_pad_numbers_are_jumpers no)
		(fp_line
			(start 1.524 -0.762)
			(end -1.524 -0.762)
			(stroke
				(width 0.1524)
				(type default)
			)
			(layer "B.SilkS")
		)
		(fp_line
			(start -1.524 -0.762)
			(end -1.524 0.762)
			(stroke
				(width 0.1524)
				(type default)
			)
			(layer "B.SilkS")
		)
		(fp_line
			(start 1.524 0.762)
			(end 1.524 -0.762)
			(stroke
				(width 0.1524)
				(type default)
			)
			(layer "B.SilkS")
		)
		(fp_line
			(start -1.524 0.762)
			(end 1.524 0.762)
			(stroke
				(width 0.1524)
				(type default)
			)
			(layer "B.SilkS")
		)
		(fp_line
			(start 1.1049 -0.724916)
			(end 1.1049 0.724916)
			(stroke
				(width 0.1)
				(type default)
			)
			(layer "B.Fab")
		)
		(fp_line
			(start -1.1049 -0.724916)
			(end 1.1049 -0.724916)
			(stroke
				(width 0.1)
				(type default)
			)
			(layer "B.Fab")
		)
		(fp_line
			(start 1.1049 0.724916)
			(end -1.1049 0.724916)
			(stroke
				(width 0.1)
				(type default)
			)
			(layer "B.Fab")
		)
		(fp_line
			(start -1.1049 0.724916)
			(end -1.1049 -0.724916)
			(stroke
				(width 0.1)
				(type default)
			)
			(layer "B.Fab")
		)
		(pad "1" smd rect
			(at 0.889 0 90)
			(size 1.016 1.27)
			(layers "B.Cu" "B.Mask" "B.Paste")
			(net "PVDDCR_SOC_P1")
		)
		(pad "2" smd rect
			(at -0.889 0 90)
			(size 1.016 1.27)
			(layers "B.Cu" "B.Mask" "B.Paste")
			(net "GND")
		)
	)
)
